FILE_TYPE = CONNECTIVITY;
{Allegro Design Entry HDL 17.4-2019 S026 (4007227) 1/17/2022}
"PAGE_NUMBER" = 391;
0"NC";
1"GND\g";
2"GND\g";
3"GND\g";
4"P1V8_CPU1_RT_1D\g";
5"RT_CPU1_P1_VQPS";
6"P1V8_CPU1_RT1_1A\g";
7"P1V8_CPU1_RT1_1A_1D\g";
8"GND\g";
9"NCF_CPU1_P1_GND";
10"GND\g";
11"P0V9_CPU1_RT1_2A\g";
12"P0V9_CPU1_RT1_2A_2D\g";
13"NCF_A1_CPU1_P1_GND";
14"P0V9_CPU1_RT_2D\g";
%"VCC_CORE"
"1","(-5075,4575)","0","pure_quanta_power","I10";
;
HDL_POWER"P0V9_CPU1_RT1_2A_2D"
CDS_LIB"pure_quanta_power";
"A"12;
%"VCC_CORE"
"1","(-4500,5050)","0","pure_quanta_power","I11";
;
HDL_POWER"P0V9_CPU1_RT1_2A"
CDS_LIB"pure_quanta_power";
"A"11;
%"UNIVERSAL_GND"
"1","(-2950,1350)","0","pure_quanta_power","I12";
;
CDS_LIB"pure_quanta_power"
HDL_POWER"GND";
"A"8;
%"P1V0"
"1","(-4475,3825)","0","pure_quanta_power","I13";
;
HDL_POWER"P0V9_CPU1_RT_2D"
CDS_LIB"pure_quanta_power";
"A"14;
%"UNIVERSAL_GND"
"1","(-1275,975)","0","pure_quanta_power","I14";
;
CDS_LIB"pure_quanta_power"
HDL_POWER"GND";
"A"1;
%"Q_RES"
"2","(-1275,1275)","0","pure_quanta","I15";
;
LOCATION"R6733"
$SEC"1"
CDS_SEC"1"
PACK_TYPE"0201LF"
VALUE"0"
TOLERANCE"5%"
MATERIAL"CHIP"
WATTAGE"1/20W"
CDS_LIB"pure_quanta"
PART_NUMBER"CS00001JE10";
"A"
$PN"1"9;
"B"
$PN"2"1;
%"Q_RES"
"2","(-1125,1825)","0","pure_quanta","I16";
;
LOCATION"R6732"
$SEC"1"
CDS_SEC"1"
PACK_TYPE"0201LF"
VALUE"0"
TOLERANCE"5%"
MATERIAL"CHIP"
WATTAGE"1/20W"
CDS_LIB"pure_quanta"
PART_NUMBER"CS00001JE10";
"A"
$PN"1"13;
"B"
$PN"2"2;
%"UNIVERSAL_GND"
"1","(-900,2075)","0","pure_quanta_power","I17";
;
CDS_LIB"pure_quanta_power"
HDL_POWER"GND";
"A"10;
%"UNIVERSAL_GND"
"1","(-1125,1525)","0","pure_quanta_power","I18";
;
CDS_LIB"pure_quanta_power"
HDL_POWER"GND";
"A"2;
%"PT5161LRS"
"5","(-2250,3600)","0","pure_quanta","I19";
;
LOCATION"U6015"
$SEC"5"
CDS_SEC"5"
PART_TYPE"SMLF"
VALUE"PT5161LRS"
MATERIAL"IC"
NEEDS_NO_SIZE"TRUE"
CDS_LMAN_SYM_OUTLINE"-350,2150,300,-2150"
CDS_LIB"pure_quanta"
PART_NUMBER"AJ051610U03";
"GND151"
$PN"V35"10;
"GND150"
$PN"V1"10;
"GND149"
$PN"U34"10;
"GND148"
$PN"U2"10;
"GND147"
$PN"T4"10;
"GND146"
$PN"T32"10;
"GND145"
$PN"T22"10;
"GND144"
$PN"T13"10;
"GND143"
$PN"L35"10;
"GND142"
$PN"L1"10;
"GND141"
$PN"K34"10;
"GND140"
$PN"K2"10;
"GND139"
$PN"J4"10;
"GND138"
$PN"J22"10;
"GND137"
$PN"H31"10;
"GND136"
$PN"H19"10;
"GND135"
$PN"H16"10;
"GND134"
$PN"H12"10;
"GND133"
$PN"FJ19"10;
"GND132"
$PN"FJ12"10;
"GND131"
$PN"FF21"10;
"GND130"
$PN"FF14"10;
"GND129"
$PN"FD35"10;
"GND128"
$PN"FD1"10;
"GND127"
$PN"FC9"10;
"GND126"
$PN"FC6"10;
"GND125"
$PN"FC3"10;
"GND124"
$PN"FC28"10;
"GND123"
$PN"FC25"10;
"GND122"
$PN"FC23"10;
"GND121"
$PN"FC19"10;
"GND120"
$PN"FB34"10;
"GND119"
$PN"FB2"10;
"GND118"
$PN"FA32"10;
"GND117"
$PN"FA15"10;
"GND116"
$PN"ET35"10;
"GND115"
$PN"ET1"10;
"GND114"
$PN"ER34"10;
"GND113"
$PN"ER2"10;
"GND112"
$PN"EP4"10;
"GND111"
$PN"EP32"10;
"GND110"
$PN"EP22"10;
"GND109"
$PN"EP13"10;
"GND108"
$PN"EJ35"10;
"GND107"
$PN"EJ1"10;
"GND106"
$PN"EH34"10;
"GND105"
$PN"EH2"10;
"GND104"
$PN"EG4"10;
"GND103"
$PN"EG32"10;
"GND102"
$PN"EG22"10;
"GND101"
$PN"EG13"10;
"GND100"
$PN"EB35"10;
"GND99"
$PN"EB1"10;
"GND98"
$PN"EA34"10;
"GND97"
$PN"EA2"10;
"GND96"
$PN"E33"10;
"GND95"
$PN"E27"10;
"GND94"
$PN"E14"10;
"GND93"
$PN"DY4"10;
"GND92"
$PN"DY32"10;
"GND91"
$PN"DY22"10;
"GND90"
$PN"DY13"10;
"GND89"
$PN"DR35"10;
"GND88"
$PN"DR1"10;
"GND87"
$PN"DP34"10;
"GND86"
$PN"DP2"10;
"GND85"
$PN"DN4"10;
"GND84"
$PN"DN32"10;
"GND83"
$PN"DN22"10;
"NCF_GND12"
$PN"FH34"9;
"NCF_GND11"
$PN"FH2"9;
"NCF_GND10"
$PN"FG35"9;
"NCF_GND9"
$PN"FG1"9;
"NCF_GND8"
$PN"FE34"9;
"NCF_GND7"
$PN"FE2"9;
"NCF_GND6"
$PN"D35"9;
"NCF_GND5"
$PN"D1"9;
"NCF_GND4"
$PN"C34"9;
"NCF_GND3"
$PN"C2"9;
"NCF_GND2"
$PN"A35"9;
"NCF_GND1"
$PN"A1"13;
"GND82"
$PN"DN13"8;
"GND81"
$PN"DH35"8;
"GND80"
$PN"DH1"8;
"GND79"
$PN"DG34"8;
"GND78"
$PN"DG2"8;
"GND77"
$PN"DF4"8;
"GND76"
$PN"DF32"8;
"GND75"
$PN"DF22"8;
"GND74"
$PN"DF13"8;
"GND73"
$PN"DA35"8;
"GND72"
$PN"DA1"8;
"GND71"
$PN"CY34"8;
"GND70"
$PN"CY2"8;
"GND69"
$PN"CW4"8;
"GND68"
$PN"CW32"8;
"GND67"
$PN"CW22"8;
"GND66"
$PN"CW13"8;
"GND65"
$PN"CP35"8;
"GND64"
$PN"CP1"8;
"GND63"
$PN"CN34"8;
"GND62"
$PN"CN2"8;
"GND61"
$PN"CM4"8;
"GND60"
$PN"CM32"8;
"GND59"
$PN"CM22"8;
"GND58"
$PN"CM13"8;
"GND57"
$PN"CG35"8;
"GND56"
$PN"CG1"8;
"GND55"
$PN"CF34"8;
"GND54"
$PN"CF2"8;
"GND53"
$PN"CE4"8;
"GND52"
$PN"CE32"8;
"GND51"
$PN"CE22"8;
"GND50"
$PN"CE13"8;
"GND49"
$PN"BY35"8;
"GND48"
$PN"BY1"8;
"GND47"
$PN"BW34"8;
"GND46"
$PN"BW2"8;
"GND45"
$PN"BV4"8;
"GND44"
$PN"BV32"8;
"GND43"
$PN"BV22"8;
"GND42"
$PN"BV13"8;
"GND41"
$PN"BN35"8;
"GND40"
$PN"BN1"8;
"GND39"
$PN"BM34"8;
"GND38"
$PN"BM2"8;
"GND37"
$PN"BL4"8;
"GND36"
$PN"BL32"8;
"GND35"
$PN"BL22"8;
"GND34"
$PN"BL13"8;
"GND33"
$PN"BF35"8;
"GND32"
$PN"BF1"8;
"GND31"
$PN"BE34"8;
"GND30"
$PN"BE2"8;
"GND29"
$PN"BD4"8;
"GND28"
$PN"BD32"8;
"GND27"
$PN"BD22"8;
"GND26"
$PN"BD13"8;
"GND25"
$PN"B19"8;
"GND24"
$PN"AW35"8;
"GND23"
$PN"AW1"8;
"GND22"
$PN"AV34"8;
"GND21"
$PN"AV2"8;
"GND20"
$PN"AU4"8;
"GND19"
$PN"AU32"8;
"GND18"
$PN"AU22"8;
"GND17"
$PN"AU13"8;
"GND16"
$PN"AM35"8;
"GND15"
$PN"AM1"8;
"GND14"
$PN"AL34"8;
"GND13"
$PN"AL2"8;
"GND12"
$PN"AK4"8;
"GND11"
$PN"AK32"8;
"GND10"
$PN"AK22"8;
"GND9"
$PN"AK13"8;
"GND8"
$PN"AE35"8;
"GND7"
$PN"AE1"8;
"GND6"
$PN"AD34"8;
"GND5"
$PN"AD2"8;
"GND4"
$PN"AC4"8;
"GND3"
$PN"AC32"8;
"GND2"
$PN"AC22"8;
"GND1"
$PN"AC13"8;
%"Q_RES"
"2","(-7475,3375)","0","pure_quanta","I20";
;
LOCATION"R6731"
$SEC"1"
CDS_SEC"1"
VALUE"200"
WATTAGE"1/20W"
TOLERANCE"1%"
MATERIAL"CHIP"
PACK_TYPE"0201LF"
CDS_LIB"pure_quanta"
PART_NUMBER"CS12001FE12";
"A"
$PN"1"5;
"B"
$PN"2"3;
%"Q_RES"
"2","(-8500,3925)","0","pure_quanta","I21";
;
LOCATION"R6730"
$SEC"1"
CDS_SEC"1"
VALUE"1K"
TOLERANCE"1%"
PACK_TYPE"0201LF"
MATERIAL"EMPTY"
WATTAGE"1/20W"
CDS_LIB"pure_quanta"
PART_NUMBER"CS21001FE07";
"A"
$PN"1"4;
"B"
$PN"2"5;
%"UNIVERSAL_GND"
"1","(-7475,3125)","0","pure_quanta_power","I3";
;
CDS_LIB"pure_quanta_power"
HDL_POWER"GND";
"A"3;
%"PT5161LRS"
"4","(-6325,4175)","0","pure_quanta","I5";
;
LOCATION"U6015"
$SEC"4"
CDS_SEC"4"
PART_TYPE"SMLF"
VALUE"PT5161LRS"
MATERIAL"IC"
NEEDS_NO_SIZE"TRUE"
CDS_LMAN_SYM_OUTLINE"-450,750,400,-750"
CDS_LIB"pure_quanta"
PART_NUMBER"AJ051610U03";
"PWR_2A_20"
$PN"T20"11;
"PWR_2A_19"
$PN"T17"11;
"PWR_2A_18"
$PN"EP20"11;
"PWR_2A_17"
$PN"EP17"11;
"PWR_2A_16"
$PN"EG20"11;
"PWR_2A_15"
$PN"EG17"11;
"PWR_2A_14"
$PN"DY20"11;
"PWR_2A_13"
$PN"DY17"11;
"PWR_2A_12"
$PN"DN20"11;
"PWR_2A_11"
$PN"DN17"11;
"PWR_2A_10"
$PN"DF20"12;
"PWR_2A_9"
$PN"DF17"12;
"PWR_2A_8"
$PN"BD20"12;
"PWR_2A_7"
$PN"BD17"12;
"PWR_2A_6"
$PN"AU20"11;
"PWR_2A_5"
$PN"AU17"11;
"PWR_2A_4"
$PN"AK20"11;
"PWR_2A_3"
$PN"AK17"11;
"PWR_2A_2"
$PN"AC20"11;
"PWR_2A_1"
$PN"AC17"11;
"PWR_1D"
$PN"BV17"7;
"PWR_2D_4"
$PN"CW20"14;
"PWR_2D_3"
$PN"CW17"14;
"PWR_2D_2"
$PN"BL20"14;
"PWR_2D_1"
$PN"BL17"14;
"PWR_1A_5"
$PN"CM20"6;
"PWR_1A_4"
$PN"CM17"6;
"PWR_1A_3"
$PN"CE20"6;
"PWR_1A_2"
$PN"CE17"6;
"PWR_1A_1"
$PN"BV20"6;
"VQPS"
$PN"G1"5;
%"P1V0"
"1","(-8500,4150)","0","pure_quanta_power","I7";
;
HDL_POWER"P1V8_CPU1_RT_1D"
CDS_LIB"pure_quanta_power";
"A"4;
%"P1V0"
"1","(-8175,4425)","0","pure_quanta_power","I8";
;
HDL_POWER"P1V8_CPU1_RT1_1A_1D"
CDS_LIB"pure_quanta_power";
"A"7;
%"P1V0"
"1","(-7600,4875)","0","pure_quanta_power","I9";
;
HDL_POWER"P1V8_CPU1_RT1_1A"
CDS_LIB"pure_quanta_power";
"A"6;
END.
